(kicad_pcb
	(version 20240108)
	(generator "pcbnew")
	(generator_version "8.0")
	(general
		(thickness 1.6)
		(legacy_teardrops no)
	)
	(paper "A4")
	(title_block
		(title "Jetson Orin Baseboard OCuLink Expansion")
		(date "2025-03-18")
		(rev "1.1.0")
		(company "Antmicro Ltd")
		(comment 1 "www.antmicro.com")
		(comment 9 "footprints 38-38 of 119")
	)
	(layers
		(0 "F.Cu" signal)
		(1 "In1.Cu" signal)
		(2 "In2.Cu" signal)
		(31 "B.Cu" signal)
		(32 "B.Adhes" user "B.Adhesive")
		(33 "F.Adhes" user "F.Adhesive")
		(34 "B.Paste" user)
		(35 "F.Paste" user)
		(36 "B.SilkS" user "B.Silkscreen")
		(37 "F.SilkS" user "F.Silkscreen")
		(38 "B.Mask" user)
		(39 "F.Mask" user)
		(40 "Dwgs.User" user "User.Drawings")
		(41 "Cmts.User" user "User.Comments")
		(42 "Eco1.User" user "User.Eco1")
		(43 "Eco2.User" user "User.Eco2")
		(44 "Edge.Cuts" user)
		(45 "Margin" user)
		(46 "B.CrtYd" user "B.Courtyard")
		(47 "F.CrtYd" user "F.Courtyard")
		(48 "B.Fab" user)
		(49 "F.Fab" user)
	)
	(footprint "antmicro-footprints:Conn_Plug_Samtec_ERM8_2x40_ERM8-040-05.0-L-DV-K-TR"
		(layer "F.Cu")
		(at 136.901 119.999 -90)
		(property "Reference" "J2"
			(at -17.699 3.301 90)
			(layer "F.SilkS")
			(effects
				(font
					(size 0.7 0.7)
					(thickness 0.15)
				)
				(justify left bottom)
			)
		)
		(property "Value" "Plug_Samtec_ERM8_2x40_ERM8-040-05.0-L-DV-K-TR"
			(at 0 4.2 90)
			(layer "F.Fab")
			(effects
				(font
					(size 0.7 0.7)
					(thickness 0.15)
				)
				(justify right top)
			)
		)
		(property "Footprint" "antmicro-footprints:Conn_Plug_Samtec_ERM8_2x40_ERM8-040-05.0-L-DV-K-TR"
			(at 0 0 90)
			(layer "F.Fab")
			(hide yes)
			(effects
				(font
					(size 1.27 1.27)
					(thickness 0.15)
				)
			)
		)
		(property "Datasheet" "https://suddendocs.samtec.com/catalog_english/erf8.pdf"
			(at 0 0 90)
			(layer "F.Fab")
			(hide yes)
			(effects
				(font
					(size 1.27 1.27)
					(thickness 0.15)
				)
			)
		)
		(property "Description" "80 Position Connector Header, Center Strip Contacts Surface Mount Gold"
			(at 0 0 90)
			(layer "F.Fab")
			(hide yes)
			(effects
				(font
					(size 1.27 1.27)
					(thickness 0.15)
				)
			)
		)
		(property "MPN" "ERM8-040-05.0-L-DV-K-TR"
			(at 0 0 -90)
			(unlocked yes)
			(layer "F.Fab")
			(hide yes)
			(effects
				(font
					(size 1 1)
					(thickness 0.15)
				)
			)
		)
		(property "Manufacturer" "Samtec"
			(at 0 0 -90)
			(unlocked yes)
			(layer "F.Fab")
			(hide yes)
			(effects
				(font
					(size 1 1)
					(thickness 0.15)
				)
			)
		)
		(property "Author" "Antmicro"
			(at 0 0 -90)
			(unlocked yes)
			(layer "F.Fab")
			(hide yes)
			(effects
				(font
					(size 1 1)
					(thickness 0.15)
				)
			)
		)
		(property "License" "Apache-2.0"
			(at 0 0 -90)
			(unlocked yes)
			(layer "F.Fab")
			(hide yes)
			(effects
				(font
					(size 1 1)
					(thickness 0.15)
				)
			)
		)
		(property "Pitch" "0.8 mm"
			(at 0 0 -90)
			(unlocked yes)
			(layer "F.Fab")
			(hide yes)
			(effects
				(font
					(size 1 1)
					(thickness 0.15)
				)
			)
		)
		(sheetname "Root")
		(sheetfile "jetson-orin-baseboard-oculink-expansion.kicad_sch")
		(attr smd)
		(fp_line
			(start -19 2.797)
			(end 18.998 2.797)
			(stroke
				(width 0.15)
				(type solid)
			)
			(layer "F.SilkS")
		)
		(fp_line
			(start -19 2.797)
			(end -19 -1.2)
			(stroke
				(width 0.15)
				(type solid)
			)
			(layer "F.SilkS")
		)
		(fp_line
			(start -17.401 -2.801)
			(end -19 -1.2)
			(stroke
				(width 0.15)
				(type solid)
			)
			(layer "F.SilkS")
		)
		(fp_line
			(start 18.998 -2.801)
			(end 18.998 2.797)
			(stroke
				(width 0.15)
				(type solid)
			)
			(layer "F.SilkS")
		)
		(fp_line
			(start 18.998 -2.801)
			(end -17.401 -2.801)
			(stroke
				(width 0.15)
				(type solid)
			)
			(layer "F.SilkS")
		)
		(fp_circle
			(center -16.15 -3.4)
			(end -16.1 -3.4)
			(stroke
				(width 0.15)
				(type solid)
			)
			(fill none)
			(layer "F.SilkS")
		)
		(fp_rect
			(start -19.25 -3.06)
			(end 19.23 3.03)
			(stroke
				(width 0.05)
				(type solid)
			)
			(fill none)
			(layer "F.CrtYd")
		)
		(fp_line
			(start -19 2.797)
			(end -19 -1.2)
			(stroke
				(width 0.15)
				(type solid)
			)
			(layer "F.Fab")
		)
		(fp_line
			(start 18.998 2.797)
			(end -19 2.797)
			(stroke
				(width 0.15)
				(type solid)
			)
			(layer "F.Fab")
		)
		(fp_line
			(start -19 -1.2)
			(end -17.401 -2.801)
			(stroke
				(width 0.15)
				(type solid)
			)
			(layer "F.Fab")
		)
		(fp_line
			(start -17.401 -2.801)
			(end 18.998 -2.801)
			(stroke
				(width 0.15)
				(type solid)
			)
			(layer "F.Fab")
		)
		(fp_line
			(start 18.998 -2.801)
			(end 18.998 2.797)
			(stroke
				(width 0.15)
				(type solid)
			)
			(layer "F.Fab")
		)
		(fp_text user "License: Apache-2.0"
			(at -20 6.134 90)
			(layer "F.Fab")
			(hide yes)
			(effects
				(font
					(size 0.7 0.7)
					(thickness 0.15)
				)
				(justify right top)
			)
		)
		(fp_text user "Author: Antmicro"
			(at -20 7.334 90)
			(layer "F.Fab")
			(hide yes)
			(effects
				(font
					(size 0.7 0.7)
					(thickness 0.15)
				)
				(justify right top)
			)
		)
		(fp_text user "${REFERENCE}"
			(at -20 8.534 90)
			(layer "F.Fab")
			(hide yes)
			(effects
				(font
					(size 0.7 0.7)
					(thickness 0.15)
				)
				(justify right top)
			)
		)
		(pad "" np_thru_hole circle
			(at -17.401 1.499 270)
			(size 1.45 1.45)
			(drill 1.45)
			(layers "*.Cu" "*.Mask")
		)
		(pad "" np_thru_hole circle
			(at 17.399 1.499 270)
			(size 1.45 1.45)
			(drill 1.45)
			(layers "*.Cu" "*.Mask")
		)
		(pad "1" smd rect
			(at -15.599 -1.901 270)
			(size 0.5 1.1)
			(layers "F.Cu" "F.Paste" "F.Mask")
			(net 51 "GND")
			(pintype "passive")
		)
		(pad "2" smd rect
			(at -15.599 1.898 270)
			(size 0.5 1.1)
			(layers "F.Cu" "F.Paste" "F.Mask")
			(net 51 "GND")
			(pintype "passive")
		)
		(pad "3" smd rect
			(at -14.801 -1.901 270)
			(size 0.5 1.1)
			(layers "F.Cu" "F.Paste" "F.Mask")
			(net 87 "/PCIE_{I}_TX1-")
			(pintype "passive")
		)
		(pad "4" smd rect
			(at -14.801 1.898 270)
			(size 0.5 1.1)
			(layers "F.Cu" "F.Paste" "F.Mask")
			(net 51 "GND")
			(pintype "passive")
		)
		(pad "5" smd rect
			(at -14 -1.901 270)
			(size 0.5 1.1)
			(layers "F.Cu" "F.Paste" "F.Mask")
			(net 86 "/PCIE_{I}_TX1+")
			(pintype "passive")
		)
		(pad "6" smd rect
			(at -14 1.898 270)
			(size 0.5 1.1)
			(layers "F.Cu" "F.Paste" "F.Mask")
			(net 75 "/PCIE_{I}_RX1-")
			(pintype "passive")
		)
		(pad "7" smd rect
			(at -13.202 -1.901 270)
			(size 0.5 1.1)
			(layers "F.Cu" "F.Paste" "F.Mask")
			(net 51 "GND")
			(pintype "passive")
		)
		(pad "8" smd rect
			(at -13.202 1.898 270)
			(size 0.5 1.1)
			(layers "F.Cu" "F.Paste" "F.Mask")
			(net 79 "/PCIE_{I}_RX1+")
			(pintype "passive")
		)
		(pad "9" smd rect
			(at -12.401 -1.901 270)
			(size 0.5 1.1)
			(layers "F.Cu" "F.Paste" "F.Mask")
			(net 85 "/PCIE_{I}_TX0-")
			(pintype "passive")
		)
		(pad "10" smd rect
			(at -12.401 1.898 270)
			(size 0.5 1.1)
			(layers "F.Cu" "F.Paste" "F.Mask")
			(net 51 "GND")
			(pintype "passive")
		)
		(pad "11" smd rect
			(at -11.599 -1.901 270)
			(size 0.5 1.1)
			(layers "F.Cu" "F.Paste" "F.Mask")
			(net 88 "/PCIE_{I}_TX0+")
			(pintype "passive")
		)
		(pad "12" smd rect
			(at -11.599 1.898 270)
			(size 0.5 1.1)
			(layers "F.Cu" "F.Paste" "F.Mask")
			(net 74 "/PCIE_{I}_RX0-")
			(pintype "passive")
		)
		(pad "13" smd rect
			(at -10.801 -1.901 270)
			(size 0.5 1.1)
			(layers "F.Cu" "F.Paste" "F.Mask")
			(net 51 "GND")
			(pintype "passive")
		)
		(pad "14" smd rect
			(at -10.801 1.898 270)
			(size 0.5 1.1)
			(layers "F.Cu" "F.Paste" "F.Mask")
			(net 78 "/PCIE_{I}_RX0+")
			(pintype "passive")
		)
		(pad "15" smd rect
			(at -10 -1.901 270)
			(size 0.5 1.1)
			(layers "F.Cu" "F.Paste" "F.Mask")
			(net 55 "/PCIE_CLK-")
			(pintype "passive")
		)
		(pad "16" smd rect
			(at -10 1.898 270)
			(size 0.5 1.1)
			(layers "F.Cu" "F.Paste" "F.Mask")
			(net 51 "GND")
			(pintype "passive")
		)
		(pad "17" smd rect
			(at -9.202 -1.901 270)
			(size 0.5 1.1)
			(layers "F.Cu" "F.Paste" "F.Mask")
			(net 53 "/PCIE_CLK+")
			(pintype "passive")
		)
		(pad "18" smd rect
			(at -9.202 1.898 270)
			(size 0.5 1.1)
			(layers "F.Cu" "F.Paste" "F.Mask")
			(net 15 "unconnected-(J2-Pad18)")
			(pintype "passive+no_connect")
		)
		(pad "19" smd rect
			(at -8.401 -1.901 270)
			(size 0.5 1.1)
			(layers "F.Cu" "F.Paste" "F.Mask")
			(net 51 "GND")
			(pintype "passive")
		)
		(pad "20" smd rect
			(at -8.401 1.898 270)
			(size 0.5 1.1)
			(layers "F.Cu" "F.Paste" "F.Mask")
			(net 48 "unconnected-(J2-Pad20)")
			(pintype "passive+no_connect")
		)
		(pad "21" smd rect
			(at -7.601 -1.901 270)
			(size 0.5 1.1)
			(layers "F.Cu" "F.Paste" "F.Mask")
			(net 35 "unconnected-(J2-Pad21)")
			(pintype "passive+no_connect")
		)
		(pad "22" smd rect
			(at -7.601 1.898 270)
			(size 0.5 1.1)
			(layers "F.Cu" "F.Paste" "F.Mask")
			(net 51 "GND")
			(pintype "passive")
		)
		(pad "23" smd rect
			(at -6.8 -1.901 270)
			(size 0.5 1.1)
			(layers "F.Cu" "F.Paste" "F.Mask")
			(net 13 "unconnected-(J2-Pad23)")
			(pintype "passive+no_connect")
		)
		(pad "24" smd rect
			(at -6.8 1.898 270)
			(size 0.5 1.1)
			(layers "F.Cu" "F.Paste" "F.Mask")
			(net 11 "unconnected-(J2-Pad24)")
			(pintype "passive+no_connect")
		)
		(pad "25" smd rect
			(at -6 -1.901 270)
			(size 0.5 1.1)
			(layers "F.Cu" "F.Paste" "F.Mask")
			(net 51 "GND")
			(pintype "passive")
		)
		(pad "26" smd rect
			(at -6 1.898 270)
			(size 0.5 1.1)
			(layers "F.Cu" "F.Paste" "F.Mask")
			(net 14 "unconnected-(J2-Pad26)")
			(pintype "passive+no_connect")
		)
		(pad "27" smd rect
			(at -5.202 -1.901 270)
			(size 0.5 1.1)
			(layers "F.Cu" "F.Paste" "F.Mask")
			(net 59 "/~{PCIE_RST}")
			(pintype "passive")
		)
		(pad "28" smd rect
			(at -5.202 1.898 270)
			(size 0.5 1.1)
			(layers "F.Cu" "F.Paste" "F.Mask")
			(net 51 "GND")
			(pintype "passive")
		)
		(pad "29" smd rect
			(at -4.401 -1.901 270)
			(size 0.5 1.1)
			(layers "F.Cu" "F.Paste" "F.Mask")
			(net 46 "unconnected-(J2-Pad29)")
			(pintype "passive+no_connect")
		)
		(pad "30" smd rect
			(at -4.401 1.898 270)
			(size 0.5 1.1)
			(layers "F.Cu" "F.Paste" "F.Mask")
			(net 33 "unconnected-(J2-Pad30)")
			(pintype "passive+no_connect")
		)
		(pad "31" smd rect
			(at -3.601 -1.901 270)
			(size 0.5 1.1)
			(layers "F.Cu" "F.Paste" "F.Mask")
			(net 27 "unconnected-(J2-Pad31)")
			(pintype "passive+no_connect")
		)
		(pad "32" smd rect
			(at -3.601 1.898 270)
			(size 0.5 1.1)
			(layers "F.Cu" "F.Paste" "F.Mask")
			(net 50 "unconnected-(J2-Pad32)")
			(pintype "passive+no_connect")
		)
		(pad "33" smd rect
			(at -2.802 -1.901 270)
			(size 0.5 1.1)
			(layers "F.Cu" "F.Paste" "F.Mask")
			(net 67 "/JOB_GPIO07")
			(pintype "passive")
		)
		(pad "34" smd rect
			(at -2.802 1.898 270)
			(size 0.5 1.1)
			(layers "F.Cu" "F.Paste" "F.Mask")
			(net 68 "unconnected-(J2-Pad34)")
			(pintype "passive+no_connect")
		)
		(pad "35" smd rect
			(at -2 -1.901 270)
			(size 0.5 1.1)
			(layers "F.Cu" "F.Paste" "F.Mask")
			(net 65 "/JOB_GPIO09")
			(pintype "passive")
		)
		(pad "36" smd rect
			(at -2 1.898 270)
			(size 0.5 1.1)
			(layers "F.Cu" "F.Paste" "F.Mask")
			(net 45 "unconnected-(J2-Pad36)")
			(pintype "passive+no_connect")
		)
		(pad "37" smd rect
			(at -1.2 -1.901 270)
			(size 0.5 1.1)
			(layers "F.Cu" "F.Paste" "F.Mask")
			(net 51 "GND")
			(pintype "passive")
		)
		(pad "38" smd rect
			(at -1.2 1.898 270)
			(size 0.5 1.1)
			(layers "F.Cu" "F.Paste" "F.Mask")
			(net 51 "GND")
			(pintype "passive")
		)
		(pad "39" smd rect
			(at -0.404 -1.901 270)
			(size 0.5 1.1)
			(layers "F.Cu" "F.Paste" "F.Mask")
			(net 38 "unconnected-(J2-Pad39)")
			(pintype "passive+no_connect")
		)
		(pad "40" smd rect
			(at -0.404 1.898 270)
			(size 0.5 1.1)
			(layers "F.Cu" "F.Paste" "F.Mask")
			(net 26 "unconnected-(J2-Pad40)")
			(pintype "passive+no_connect")
		)
		(pad "41" smd rect
			(at 0.4 -1.901 270)
			(size 0.5 1.1)
			(layers "F.Cu" "F.Paste" "F.Mask")
			(net 40 "unconnected-(J2-Pad41)")
			(pintype "passive+no_connect")
		)
		(pad "42" smd rect
			(at 0.4 1.898 270)
			(size 0.5 1.1)
			(layers "F.Cu" "F.Paste" "F.Mask")
			(net 29 "unconnected-(J2-Pad42)")
			(pintype "passive+no_connect")
		)
		(pad "43" smd rect
			(at 1.199 -1.901 270)
			(size 0.5 1.1)
			(layers "F.Cu" "F.Paste" "F.Mask")
			(net 24 "unconnected-(J2-Pad43)")
			(pintype "passive+no_connect")
		)
		(pad "44" smd rect
			(at 1.199 1.898 270)
			(size 0.5 1.1)
			(layers "F.Cu" "F.Paste" "F.Mask")
			(net 42 "unconnected-(J2-Pad44)")
			(pintype "passive+no_connect")
		)
		(pad "45" smd rect
			(at 1.999 -1.901 270)
			(size 0.5 1.1)
			(layers "F.Cu" "F.Paste" "F.Mask")
			(net 39 "unconnected-(J2-Pad45)")
			(pintype "passive+no_connect")
		)
		(pad "46" smd rect
			(at 1.999 1.898 270)
			(size 0.5 1.1)
			(layers "F.Cu" "F.Paste" "F.Mask")
			(net 49 "unconnected-(J2-Pad46)")
			(pintype "passive+no_connect")
		)
		(pad "47" smd rect
			(at 2.797 -1.901 270)
			(size 0.5 1.1)
			(layers "F.Cu" "F.Paste" "F.Mask")
			(net 19 "unconnected-(J2-Pad47)")
			(pintype "passive+no_connect")
		)
		(pad "48" smd rect
			(at 2.797 1.898 270)
			(size 0.5 1.1)
			(layers "F.Cu" "F.Paste" "F.Mask")
			(net 43 "unconnected-(J2-Pad48)")
			(pintype "passive+no_connect")
		)
		(pad "49" smd rect
			(at 3.6 -1.901 270)
			(size 0.5 1.1)
			(layers "F.Cu" "F.Paste" "F.Mask")
			(net 51 "GND")
			(pintype "passive")
		)
		(pad "50" smd rect
			(at 3.6 1.898 270)
			(size 0.5 1.1)
			(layers "F.Cu" "F.Paste" "F.Mask")
			(net 51 "GND")
			(pintype "passive")
		)
		(pad "51" smd rect
			(at 4.4 -1.901 270)
			(size 0.5 1.1)
			(layers "F.Cu" "F.Paste" "F.Mask")
			(net 22 "unconnected-(J2-Pad51)")
			(pintype "passive+no_connect")
		)
		(pad "52" smd rect
			(at 4.4 1.898 270)
			(size 0.5 1.1)
			(layers "F.Cu" "F.Paste" "F.Mask")
			(net 28 "unconnected-(J2-Pad52)")
			(pintype "passive+no_connect")
		)
		(pad "53" smd rect
			(at 5.2 -1.901 270)
			(size 0.5 1.1)
			(layers "F.Cu" "F.Paste" "F.Mask")
			(net 10 "unconnected-(J2-Pad53)")
			(pintype "passive+no_connect")
		)
		(pad "54" smd rect
			(at 5.2 1.898 270)
			(size 0.5 1.1)
			(layers "F.Cu" "F.Paste" "F.Mask")
			(net 18 "unconnected-(J2-Pad54)")
			(pintype "passive+no_connect")
		)
		(pad "55" smd rect
			(at 5.998 -1.901 270)
			(size 0.5 1.1)
			(layers "F.Cu" "F.Paste" "F.Mask")
			(net 25 "unconnected-(J2-Pad55)")
			(pintype "passive+no_connect")
		)
		(pad "56" smd rect
			(at 5.998 1.898 270)
			(size 0.5 1.1)
			(layers "F.Cu" "F.Paste" "F.Mask")
			(net 34 "unconnected-(J2-Pad56)")
			(pintype "passive+no_connect")
		)
		(pad "57" smd rect
			(at 6.799 -1.901 270)
			(size 0.5 1.1)
			(layers "F.Cu" "F.Paste" "F.Mask")
			(net 21 "unconnected-(J2-Pad57)")
			(pintype "passive+no_connect")
		)
		(pad "58" smd rect
			(at 6.799 1.898 270)
			(size 0.5 1.1)
			(layers "F.Cu" "F.Paste" "F.Mask")
			(net 12 "unconnected-(J2-Pad58)")
			(pintype "passive+no_connect")
		)
		(pad "59" smd rect
			(at 7.599 -1.901 270)
			(size 0.5 1.1)
			(layers "F.Cu" "F.Paste" "F.Mask")
			(net 17 "unconnected-(J2-Pad59)")
			(pintype "passive+no_connect")
		)
		(pad "60" smd rect
			(at 7.599 1.898 270)
			(size 0.5 1.1)
			(layers "F.Cu" "F.Paste" "F.Mask")
			(net 41 "unconnected-(J2-Pad60)")
			(pintype "passive+no_connect")
		)
		(pad "61" smd rect
			(at 8.4 -1.901 270)
			(size 0.5 1.1)
			(layers "F.Cu" "F.Paste" "F.Mask")
			(net 51 "GND")
			(pintype "passive")
		)
		(pad "62" smd rect
			(at 8.4 1.898 270)
			(size 0.5 1.1)
			(layers "F.Cu" "F.Paste" "F.Mask")
			(net 51 "GND")
			(pintype "passive")
		)
		(pad "63" smd rect
			(at 9.198 -1.901 270)
			(size 0.5 1.1)
			(layers "F.Cu" "F.Paste" "F.Mask")
			(net 61 "/I2C_SDA")
			(pintype "passive")
		)
		(pad "64" smd rect
			(at 9.198 1.898 270)
			(size 0.5 1.1)
			(layers "F.Cu" "F.Paste" "F.Mask")
			(net 32 "unconnected-(J2-Pad64)")
			(pintype "passive+no_connect")
		)
		(pad "65" smd rect
			(at 9.999 -1.901 270)
			(size 0.5 1.1)
			(layers "F.Cu" "F.Paste" "F.Mask")
			(net 64 "/I2C_SCL")
			(pintype "passive")
		)
		(pad "66" smd rect
			(at 9.999 1.898 270)
			(size 0.5 1.1)
			(layers "F.Cu" "F.Paste" "F.Mask")
			(net 47 "unconnected-(J2-Pad66)")
			(pintype "passive+no_connect")
		)
		(pad "67" smd rect
			(at 10.8 -1.901 270)
			(size 0.5 1.1)
			(layers "F.Cu" "F.Paste" "F.Mask")
			(net 23 "+3V3")
			(pintype "passive")
		)
		(pad "68" smd rect
			(at 10.8 1.898 270)
			(size 0.5 1.1)
			(layers "F.Cu" "F.Paste" "F.Mask")
			(net 16 "unconnected-(J2-Pad68)")
			(pintype "passive+no_connect")
		)
		(pad "69" smd rect
			(at 11.598 -1.901 270)
			(size 0.5 1.1)
			(layers "F.Cu" "F.Paste" "F.Mask")
			(net 23 "+3V3")
			(pintype "passive")
		)
		(pad "70" smd rect
			(at 11.598 1.898 270)
			(size 0.5 1.1)
			(layers "F.Cu" "F.Paste" "F.Mask")
			(net 30 "unconnected-(J2-Pad70)")
			(pintype "passive+no_connect")
		)
		(pad "71" smd rect
			(at 12.4 -1.901 270)
			(size 0.5 1.1)
			(layers "F.Cu" "F.Paste" "F.Mask")
			(net 51 "GND")
			(pintype "passive")
		)
		(pad "72" smd rect
			(at 12.4 1.898 270)
			(size 0.5 1.1)
			(layers "F.Cu" "F.Paste" "F.Mask")
			(net 51 "GND")
			(pintype "passive")
		)
		(pad "73" smd rect
			(at 13.198 -1.901 270)
			(size 0.5 1.1)
			(layers "F.Cu" "F.Paste" "F.Mask")
			(net 20 "+1V8")
			(pintype "passive")
		)
		(pad "74" smd rect
			(at 13.198 1.898 270)
			(size 0.5 1.1)
			(layers "F.Cu" "F.Paste" "F.Mask")
			(net 44 "unconnected-(J2-Pad74)")
			(pintype "passive+no_connect")
		)
		(pad "75" smd rect
			(at 13.999 -1.901 270)
			(size 0.5 1.1)
			(layers "F.Cu" "F.Paste" "F.Mask")
			(net 51 "GND")
			(pintype "passive")
		)
		(pad "76" smd rect
			(at 13.999 1.898 270)
			(size 0.5 1.1)
			(layers "F.Cu" "F.Paste" "F.Mask")
			(net 51 "GND")
			(pintype "passive")
		)
		(pad "77" smd rect
			(at 14.8 -1.901 270)
			(size 0.5 1.1)
			(layers "F.Cu" "F.Paste" "F.Mask")
			(net 52 "+5V")
			(pintype "passive")
		)
		(pad "78" smd rect
			(at 14.8 1.898 270)
			(size 0.5 1.1)
			(layers "F.Cu" "F.Paste" "F.Mask")
			(net 37 "unconnected-(J2-Pad78)")
			(pintype "passive+no_connect")
		)
		(pad "79" smd rect
			(at 15.598 -1.901 270)
			(size 0.5 1.1)
			(layers "F.Cu" "F.Paste" "F.Mask")
			(net 52 "+5V")
			(pintype "passive")
		)
		(pad "80" smd rect
			(at 15.598 1.898 270)
			(size 0.5 1.1)
			(layers "F.Cu" "F.Paste" "F.Mask")
			(net 36 "unconnected-(J2-Pad80)")
			(pintype "passive+no_connect")
		)
	)
)
